FILE_TYPE = CONNECTIVITY;
{Allegro Design Entry HDL 17.4-2019 S026 (4007227) 1/17/2022}
"PAGE_NUMBER" = 193;
0"NC";
1"GND\g";
2"GND\g";
3"GND\g";
4"GND\g";
5"P5V_AUX\g";
6"GND\g";
7"P3V3_AUX\g";
8"GND\g";
9"GND\g";
10"GND\g";
11"GND\g";
12"GND\g";
13"P12V_AUX\g";
14"GND\g";
15"PVDDCR_CPU1_P1_LSET2";
16"PVDDCR_CPU1_P1_VOS2";
17"SW_PVDDCR_CPU1_P1_SW2";
18"SW_PVDDCR_CPU1_P1_BOOTR2";
19"PVDDCR_CPU1_P1\g";
20"SW_P12V_AUX_PVDDCR_CPU1_P1_FLT\g";
21"GND\g";
22"PVDDCR_CPU1_P1_PVCC\g";
23"PVDDCR_CPU1_P1_PVCC\g";
24"GND\g";
25"GND\g";
26"GND\g";
27"SW_P12V_AUX_PVDDCR_CPU1_P1_FLT\g";
28"GND\g";
29"PVDDCR_CPU1_P1\g";
30"GND\g";
31"PVDDCR_CPU1_P1\g";
32"GND\g";
33"SW_PVDDCR_CPU1_P1_BOOT2";
34"PVDDCR_CPU1_P1_VOS1";
35"SW_PVDDCR_CPU1_P1_SW1";
36"SW_PVDDCR_CPU1_P1_BOOTR1";
37"SW_PVDDCR_CPU1_P1_BOOT1";
38"SW_PVDDCR_CPU1_P1_BOOT1_R";
39"SW_PVDDCR_CPU1_P1_BOOT2_R";
40"PVDDCR_CPU1_P1_VCCS"CDS_PHYS_NET_NAME"PVDDCR_CPU1_P1_VCCS";
41"PVDDCR_CPU1_P1_LSET1";
42"PVDDCR_CPU1_P1_IMON1";
43"PVDDCR_CPU1_P1_TEMP0";
44"PVDDCR_CPU1_P1_PWM1";
45"PVDDCR_CPU1_P1_TEMP0";
46"PVDDCR_CPU1_P1_PWM2";
47"PVDDCR_CPU1_P1_IMON2";
48"NC_PVDDCR_CPU1_P1_DNC2";
49"PVDDCR_CPU1_P1_VCC2";
50"NC_PVDDCR_CPU1_P1_GL2_2";
51"NC_PVDDCR_CPU1_P1_GL1_2";
52"SW_PVDDCR_CPU1_P1_SW2_RC";
53"SW_PVDDCR_CPU1_P1_SW1_RC";
54"NC_PVDDCR_CPU1_P1_DNC1";
55"PVDDCR_CPU1_P1_VCC1";
56"NC_PVDDCR_CPU1_P1_GL1_1";
57"NC_PVDDCR_CPU1_P1_GL2_1";
58"IND_CPU1_P1_CPL5";
59"IND_CPU1_P1_CPL1";
60"IND_CPU1_P1_CPL2";
61"IND_CPU1_P1_CPL1";
62"PVDDCR_CPU1_P1_VCCS"CDS_PHYS_NET_NAME"PVDDCR_CPU1_P1_VCCS";
%"UNIVERSAL_GND"
"1","(-9250,1400)","0","pure_quanta_power","I1";
;
CDS_LIB"pure_quanta_power"
HDL_POWER"GND";
"A"1;
%"UNIVERSAL_GND"
"1","(-9225,4025)","0","pure_quanta_power","I10";
;
CDS_LIB"pure_quanta_power"
HDL_POWER"GND";
"A"2;
%"Q_CAP"
"1","(-9225,4225)","0","pure_quanta","I11";
;
LOCATION"PC374_1"
$SEC"1"
CDS_SEC"1"
MATERIAL"X7R"
TOLERANCE"10%"
PACK_TYPE"0402"
VALUE"0.1UF"
VOLTAGE"25V"
CDS_LIB"pure_quanta"
PART_NUMBER"CH4104K1B00";
"B"
$PN"2"2;
"A"
$PN"1"62;
%"Q_CAP"
"1","(-8475,2400)","0","pure_quanta","I12";
;
LOCATION"PC370"
$SEC"1"
CDS_SEC"1"
MATERIAL"X6S"
TOLERANCE"10%"
VALUE"2.2UF"
VOLTAGE"10V"
PACK_TYPE"C0402"
CDS_LIB"pure_quanta"
PART_NUMBER"CH5222KEB01";
"B"
$PN"2"14;
"A"
$PN"1"49;
%"UNIVERSAL_GND"
"1","(-8125,2700)","0","pure_quanta_power","I13";
;
CDS_LIB"pure_quanta_power"
HDL_POWER"GND";
"A"3;
%"Q_RES"
"2","(-8475,2950)","0","pure_quanta","I14";
;
LOCATION"PR257"
$SEC"1"
CDS_SEC"1"
VALUE"2.2"
TOLERANCE"1%"
MATERIAL"CHIP"
WATTAGE"1/16W"
PACK_TYPE"0402LF"
CDS_LIB"pure_quanta"
PART_NUMBER"CS-2202FB01";
"A"
$PN"1"22;
"B"
$PN"2"49;
%"Q_CAP"
"1","(-8125,2975)","0","pure_quanta","I15";
;
LOCATION"PC372_C1P1_2"
$SEC"1"
CDS_SEC"1"
MATERIAL"X6S"
TOLERANCE"10%"
VALUE"2.2UF"
VOLTAGE"10V"
PACK_TYPE"C0402"
CDS_LIB"pure_quanta"
PART_NUMBER"CH5222KEB01";
"B"
$PN"2"3;
"A"
$PN"1"22;
%"UNIVERSAL_GND"
"1","(-8725,3875)","0","pure_quanta_power","I16";
;
CDS_LIB"pure_quanta_power"
HDL_POWER"GND";
"A"4;
%"Q_RES"
"2","(-8725,4100)","2","pure_quanta","I17";
;
LOCATION"PR255"
$SEC"1"
CDS_SEC"1"
WATTAGE"1/16W"
MATERIAL"EMPTY"
TOLERANCE"1%"
PACK_TYPE"0402LF"
VALUE"8.87K"
CDS_LIB"pure_quanta"
PART_NUMBER"CS28872FB01";
"A"
$PN"1"41;
"B"
$PN"2"4;
%"VCC_CORE"
"1","(-8475,3350)","0","pure_quanta_power","I18";
;
HDL_POWER"PVDDCR_CPU1_P1_PVCC"
CDS_LIB"pure_quanta_power";
"A"22;
%"Q_CAP"
"1","(-9250,1600)","0","pure_quanta","I2";
;
LOCATION"PC373_2"
$SEC"1"
CDS_SEC"1"
VALUE"0.1UF"
TOLERANCE"10%"
MATERIAL"X7R"
PACK_TYPE"0402"
VOLTAGE"25V"
CDS_LIB"pure_quanta"
PART_NUMBER"CH4104K1B00";
"B"
$PN"2"1;
"A"
$PN"1"40;
%"VCC_CORE"
"1","(-9225,6200)","0","pure_quanta_power","I21";
;
HDL_POWER"P5V_AUX"
CDS_LIB"pure_quanta_power";
"A"5;
%"UNIVERSAL_GND"
"1","(-8575,4850)","0","pure_quanta_power","I22";
;
CDS_LIB"pure_quanta_power"
HDL_POWER"GND";
"A"6;
%"Q_CAP"
"1","(-8575,5050)","0","pure_quanta","I23";
;
LOCATION"PC369"
$SEC"1"
CDS_SEC"1"
MATERIAL"X6S"
TOLERANCE"10%"
VALUE"2.2UF"
VOLTAGE"10V"
PACK_TYPE"C0402"
CDS_LIB"pure_quanta"
PART_NUMBER"CH5222KEB01";
"B"
$PN"2"6;
"A"
$PN"1"55;
%"VCC_CORE"
"1","(-8875,6200)","0","pure_quanta_power","I26";
;
HDL_POWER"P3V3_AUX"
CDS_LIB"pure_quanta_power";
"A"7;
%"Q_RES"
"2","(-8575,5600)","0","pure_quanta","I27";
;
LOCATION"PR256"
$SEC"1"
CDS_SEC"1"
MATERIAL"CHIP"
VALUE"2.2"
TOLERANCE"1%"
WATTAGE"1/16W"
PACK_TYPE"0402LF"
CDS_LIB"pure_quanta"
PART_NUMBER"CS-2202FB01";
"A"
$PN"1"23;
"B"
$PN"2"55;
%"UNIVERSAL_GND"
"1","(-8225,5350)","0","pure_quanta_power","I28";
;
CDS_LIB"pure_quanta_power"
HDL_POWER"GND";
"A"8;
%"Q_CAP"
"1","(-8225,5625)","0","pure_quanta","I29";
;
LOCATION"PC371_C1P1_1"
$SEC"1"
CDS_SEC"1"
MATERIAL"X6S"
TOLERANCE"10%"
VALUE"2.2UF"
VOLTAGE"10V"
PACK_TYPE"C0402"
CDS_LIB"pure_quanta"
PART_NUMBER"CH5222KEB01";
"B"
$PN"2"8;
"A"
$PN"1"23;
%"UNIVERSAL_GND"
"1","(-8750,1250)","0","pure_quanta_power","I3";
;
CDS_LIB"pure_quanta_power"
HDL_POWER"GND";
"A"9;
%"VCC_CORE"
"1","(-8375,6200)","0","pure_quanta_power","I30";
;
HDL_POWER"PVDDCR_CPU1_P1_PVCC"
CDS_LIB"pure_quanta_power";
"A"23;
%"ISL99390FRZTR5935"
"1","(-6825,1975)","0","pure_quanta","I31";
;
LOCATION"PU5"
SEC"1"
VALUE"ISL99390FRZ-TR5935"
PART_TYPE"SMLF"
MATERIAL"IC"
SEC_TYPE""
CDS_LIB"pure_quanta"
CDS_LMAN_SYM_OUTLINE"-300,700,250,-650"
NEEDS_NO_SIZE"TRUE"
PART_NUMBER"AL099390004";
"PGND2"
$PN"7_9-20_24"24;
"GL2"
$PN"41"50;
"GL1"
$PN"6"51;
"DNC"
$PN"31"48;
"EN"
$PN"35"49;
"PGND3"
$PN"40"24;
"VOS"
$PN"1"16;
"VIN2"
$PN"30"27;
"PGND1"
$PN"5"24;
"SW"
$PN"10_19"17;
"LSET"
$PN"37"15;
"IOUT"
$PN"38"47;
"TOUT_FLT"
$PN"36"45;
"PVCC"
$PN"4"22;
"PHASE"
$PN"32"18;
"VIN1"
$PN"25_29"27;
"BOOT"
$PN"33"33;
"AGND"
$PN"2"24;
"VCC"
$PN"3"49;
"REFIN"
$PN"39"40;
"PWM"
$PN"34"46;
%"UNIVERSAL_GND"
"1","(-6175,1250)","0","pure_quanta_power","I32";
;
CDS_LIB"pure_quanta_power"
HDL_POWER"GND";
"A"24;
%"UNIVERSAL_GND"
"1","(-6150,3875)","0","pure_quanta_power","I33";
;
CDS_LIB"pure_quanta_power"
HDL_POWER"GND";
"A"25;
%"Q_CAP"
"1","(-6000,2875)","0","pure_quanta","I34";
;
LOCATION"PC376_2"
$SEC"1"
CDS_SEC"1"
MATERIAL"X7R"
PACK_TYPE"0402"
TOLERANCE"10%"
VALUE"0.1UF"
VOLTAGE"25V"
CDS_LIB"pure_quanta"
PART_NUMBER"CH4104K1B00";
"B"
$PN"2"26;
"A"
$PN"1"27;
%"UNIVERSAL_GND"
"1","(-5375,1025)","0","pure_quanta_power","I35";
;
CDS_LIB"pure_quanta_power"
HDL_POWER"GND";
"A"10;
%"Q_RES"
"2","(-5375,1250)","0","pure_quanta","I36";
;
LOCATION"PR513"
$SEC"1"
CDS_SEC"1"
TOLERANCE"1%"
WATTAGE"1/8W"
MATERIAL"EMPTY"
VALUE"1.5"
PACK_TYPE"0402LF"
CDS_LIB"pure_quanta"
PART_NUMBER"CS-1504FB00";
"A"
$PN"1"52;
"B"
$PN"2"10;
%"Q_CAP"
"1","(-5375,1800)","0","pure_quanta","I37";
;
LOCATION"PC202"
$SEC"1"
CDS_SEC"1"
TOLERANCE"10%"
MATERIAL"EMPTY"
VALUE"560PF"
VOLTAGE"50V"
PACK_TYPE"C0402"
CDS_LIB"pure_quanta"
PART_NUMBER"CH1566K1B09";
"B"
$PN"2"52;
"A"
$PN"1"17;
%"Q_RES"
"1","(-4500,750)","0","pure_quanta","I38";
;
LOCATION"PR260"
$SEC"1"
CDS_SEC"1"
PACK_TYPE"0402LF"
VALUE"0"
TOLERANCE"5%"
MATERIAL"CHIP"
WATTAGE"1/16W"
CDS_LIB"pure_quanta"
PART_NUMBER"CS00002JB13";
"B"
$PN"2"29;
"A"
$PN"1"16;
%"Q_RES"
"2","(-8750,1475)","2","pure_quanta","I4";
;
LOCATION"PR254"
$SEC"1"
CDS_SEC"1"
WATTAGE"1/16W"
VALUE"8.87K"
MATERIAL"EMPTY"
TOLERANCE"1%"
PACK_TYPE"0402LF"
CDS_LIB"pure_quanta"
PART_NUMBER"CS28872FB01";
"A"
$PN"1"15;
"B"
$PN"2"9;
%"Q_CAP"
"1","(-4350,2200)","0","pure_quanta","I40";
;
LOCATION"PC386"
$SEC"1"
CDS_SEC"1"
PACK_TYPE"0402"
MATERIAL"X7R"
TOLERANCE"10%"
VOLTAGE"16V"
VALUE"0.22UF"
CDS_LIB"pure_quanta"
PART_NUMBER"CH4223K1B00";
"B"
$PN"2"18;
"A"
$PN"1"39;
%"Q_RES"
"1","(-5500,2325)","0","pure_quanta","I41";
;
LOCATION"PR259"
$SEC"1"
CDS_SEC"1"
VALUE"5.6"
PACK_TYPE"0402LF"
WATTAGE"1/16W"
MATERIAL"CHIP"
TOLERANCE"1%"
CDS_LIB"pure_quanta"
PART_NUMBER"CS-5602FB01";
"B"
$PN"2"39;
"A"
$PN"1"33;
%"Q_CAP"
"1","(-5600,2875)","0","pure_quanta","I42";
;
LOCATION"PC378_2"
$SEC"1"
CDS_SEC"1"
MATERIAL"X6S"
TOLERANCE"10%"
VOLTAGE"25V"
PACK_TYPE"C0402"
VALUE"1UF"
CDS_LIB"pure_quanta"
PART_NUMBER"CH5104KEB02";
"B"
$PN"2"26;
"A"
$PN"1"27;
%"Q_CAP"
"1","(-5200,2875)","0","pure_quanta","I43";
;
LOCATION"PC380_2"
$SEC"1"
CDS_SEC"1"
PACK_TYPE"C0805"
MATERIAL"X6S"
TOLERANCE"20%"
VALUE"22UF"
VOLTAGE"16V"
CDS_LIB"pure_quanta"
PART_NUMBER"CH6223MEA01";
"B"
$PN"2"26;
"A"
$PN"1"27;
%"UNIVERSAL_GND"
"1","(-5325,3650)","0","pure_quanta_power","I44";
;
CDS_LIB"pure_quanta_power"
HDL_POWER"GND";
"A"11;
%"Q_RES"
"2","(-5325,3875)","0","pure_quanta","I45";
;
LOCATION"PR512"
$SEC"1"
CDS_SEC"1"
WATTAGE"1/8W"
MATERIAL"EMPTY"
TOLERANCE"1%"
VALUE"1.5"
PACK_TYPE"0402LF"
CDS_LIB"pure_quanta"
PART_NUMBER"CS-1504FB00";
"A"
$PN"1"53;
"B"
$PN"2"11;
%"Q_CAP"
"1","(-4800,2875)","0","pure_quanta","I46";
;
LOCATION"PC382_2"
$SEC"1"
CDS_SEC"1"
MATERIAL"X6S"
VALUE"22UF"
VOLTAGE"16V"
TOLERANCE"20%"
PACK_TYPE"C0805"
CDS_LIB"pure_quanta"
PART_NUMBER"CH6223MEA01";
"B"
$PN"2"26;
"A"
$PN"1"27;
%"UNIVERSAL_GND"
"1","(-4425,2500)","0","pure_quanta_power","I47";
;
CDS_LIB"pure_quanta_power"
HDL_POWER"GND";
"A"26;
%"Q_CAP"
"1","(-4425,2875)","0","pure_quanta","I48";
;
LOCATION"PC385_2"
$SEC"1"
CDS_SEC"1"
VALUE"22UF"
VOLTAGE"16V"
PACK_TYPE"C0805"
MATERIAL"X6S"
TOLERANCE"20%"
CDS_LIB"pure_quanta"
PART_NUMBER"CH6223MEA01";
"B"
$PN"2"26;
"A"
$PN"1"27;
%"VCC_CORE"
"1","(-4425,3225)","0","pure_quanta_power","I49";
;
HDL_POWER"SW_P12V_AUX_PVDDCR_CPU1_P1_FLT"
CDS_LIB"pure_quanta_power";
"A"27;
%"Q_CAP"
"1","(-6025,5500)","0","pure_quanta","I50";
;
LOCATION"PC375_1"
$SEC"1"
CDS_SEC"1"
PACK_TYPE"0402"
MATERIAL"X7R"
TOLERANCE"10%"
VALUE"0.1UF"
VOLTAGE"25V"
CDS_LIB"pure_quanta"
PART_NUMBER"CH4104K1B00";
"B"
$PN"2"21;
"A"
$PN"1"20;
%"Q_RES"
"1","(-5550,4950)","0","pure_quanta","I51";
;
LOCATION"PR258"
$SEC"1"
CDS_SEC"1"
PACK_TYPE"0402LF"
WATTAGE"1/16W"
VALUE"5.6"
TOLERANCE"1%"
MATERIAL"CHIP"
CDS_LIB"pure_quanta"
PART_NUMBER"CS-5602FB01";
"B"
$PN"2"38;
"A"
$PN"1"37;
%"Q_CAP"
"1","(-5325,4400)","0","pure_quanta","I52";
;
LOCATION"PC201"
$SEC"1"
CDS_SEC"1"
MATERIAL"EMPTY"
TOLERANCE"10%"
VALUE"560PF"
VOLTAGE"50V"
PACK_TYPE"C0402"
CDS_LIB"pure_quanta"
PART_NUMBER"CH1566K1B09";
"B"
$PN"2"53;
"A"
$PN"1"35;
%"Q_CAP"
"1","(-5625,5500)","0","pure_quanta","I53";
;
LOCATION"PC377_1"
$SEC"1"
CDS_SEC"1"
TOLERANCE"10%"
MATERIAL"X6S"
VALUE"1UF"
VOLTAGE"25V"
PACK_TYPE"C0402"
CDS_LIB"pure_quanta"
PART_NUMBER"CH5104KEB02";
"B"
$PN"2"21;
"A"
$PN"1"20;
%"Q_CAP"
"1","(-5225,5500)","0","pure_quanta","I54";
;
LOCATION"PC379_1"
$SEC"1"
CDS_SEC"1"
PACK_TYPE"C0805"
MATERIAL"X6S"
VALUE"22UF"
VOLTAGE"16V"
TOLERANCE"20%"
CDS_LIB"pure_quanta"
PART_NUMBER"CH6223MEA01";
"B"
$PN"2"21;
"A"
$PN"1"20;
%"UNIVERSAL_GND"
"1","(-4575,5100)","0","pure_quanta_power","I56";
;
CDS_LIB"pure_quanta_power"
HDL_POWER"GND";
"A"21;
%"Q_CAP"
"1","(-4475,4825)","0","pure_quanta","I57";
;
LOCATION"PC383"
$SEC"1"
CDS_SEC"1"
MATERIAL"X7R"
PACK_TYPE"0402"
TOLERANCE"10%"
VOLTAGE"16V"
VALUE"0.22UF"
CDS_LIB"pure_quanta"
PART_NUMBER"CH4223K1B00";
"B"
$PN"2"36;
"A"
$PN"1"38;
%"Q_CAP"
"1","(-4825,5500)","0","pure_quanta","I58";
;
LOCATION"PC381_1"
$SEC"1"
CDS_SEC"1"
TOLERANCE"20%"
PACK_TYPE"C0805"
VALUE"22UF"
VOLTAGE"16V"
MATERIAL"X6S"
CDS_LIB"pure_quanta"
PART_NUMBER"CH6223MEA01";
"B"
$PN"2"21;
"A"
$PN"1"20;
%"VCC_CORE"
"1","(-4625,5900)","0","pure_quanta_power","I59";
;
HDL_POWER"SW_P12V_AUX_PVDDCR_CPU1_P1_FLT"
CDS_LIB"pure_quanta_power";
"A"20;
%"Q_CAP"
"1","(-4450,5500)","0","pure_quanta","I60";
;
LOCATION"PC384_1"
$SEC"1"
CDS_SEC"1"
VALUE"22UF"
TOLERANCE"20%"
PACK_TYPE"C0805"
MATERIAL"X6S"
VOLTAGE"16V"
CDS_LIB"pure_quanta"
PART_NUMBER"CH6223MEA01";
"B"
$PN"2"21;
"A"
$PN"1"20;
%"Q_INDUCTOR4P_14"
"1","(-3050,1850)","0","pure_quanta","I62";
;
LOCATION"PL41"
$SEC"1"
CDS_SEC"1"
PART_TYPE"SMLF"
MATERIAL"IND"
VALUE"150NH"
NEEDS_NO_SIZE"TRUE"
CDS_LIB"pure_quanta"
PART_NUMBER"CV+15^0TZ04";
"1"
$PN"1"17;
"4"
$PN"4"29;
"3"
$PN"3"60;
"2"
$PN"2"59;
%"Q_RES"
"1","(-3775,3575)","0","pure_quanta","I64";
;
LOCATION"PR261"
$SEC"1"
CDS_SEC"1"
VALUE"0"
PACK_TYPE"0402LF"
TOLERANCE"5%"
MATERIAL"CHIP"
WATTAGE"1/16W"
CDS_LIB"pure_quanta"
PART_NUMBER"CS00002JB13";
"B"
$PN"2"19;
"A"
$PN"1"34;
%"Q_CAPP"
"1","(-2800,2925)","0","pure_quanta","I65";
;
LOCATION"PC106"
$SEC"1"
CDS_SEC"1"
VOLTAGE"4V"
VALUE"220UF"
TOLERANCE"20%"
MATERIAL"SPCAP"
PACK_TYPE"SMLF"
CDS_LIB"pure_quanta"
PART_NUMBER"CH122KM8801";
"A"
$PN"1"31;
"B"
$PN"2"30;
%"Q_CAPP"
"1","(-2450,2925)","0","pure_quanta","I66";
;
LOCATION"PC387"
$SEC"1"
CDS_SEC"1"
PACK_TYPE"SMLF"
VALUE"220UF"
TOLERANCE"20%"
VOLTAGE"4V"
MATERIAL"SPCAP"
CDS_LIB"pure_quanta"
PART_NUMBER"CH122KM8801";
"A"
$PN"1"31;
"B"
$PN"2"30;
%"Q_CAPP"
"1","(-2125,2925)","0","pure_quanta","I67";
;
LOCATION"PC388"
$SEC"1"
CDS_SEC"1"
VALUE"220UF"
TOLERANCE"20%"
PACK_TYPE"SMLF"
VOLTAGE"4V"
MATERIAL"SPCAP"
CDS_LIB"pure_quanta"
PART_NUMBER"CH122KM8801";
"A"
$PN"1"31;
"B"
$PN"2"30;
%"Q_CAP"
"1","(-1650,1775)","0","pure_quanta","I68";
;
LOCATION"PC394_2"
$SEC"1"
CDS_SEC"1"
VOLTAGE"4V"
VALUE"22UF"
TOLERANCE"20%"
MATERIAL"X6S"
PACK_TYPE"C0805"
CDS_LIB"pure_quanta"
PART_NUMBER"CH622KMEA03";
"B"
$PN"2"28;
"A"
$PN"1"29;
%"UNIVERSAL_GND"
"1","(-1225,1450)","0","pure_quanta_power","I69";
;
CDS_LIB"pure_quanta_power"
HDL_POWER"GND";
"A"28;
%"Q_CAP"
"1","(-1225,1775)","0","pure_quanta","I70";
;
LOCATION"PC397_2"
$SEC"1"
CDS_SEC"1"
VOLTAGE"4V"
VALUE"22UF"
TOLERANCE"20%"
MATERIAL"X6S"
PACK_TYPE"C0805"
CDS_LIB"pure_quanta"
PART_NUMBER"CH622KMEA03";
"B"
$PN"2"28;
"A"
$PN"1"29;
%"VCC_CORE"
"1","(-1225,2075)","0","pure_quanta_power","I71";
;
HDL_POWER"PVDDCR_CPU1_P1"
CDS_LIB"pure_quanta_power";
"A"29;
%"UNIVERSAL_GND"
"1","(-1500,2550)","0","pure_quanta_power","I72";
;
CDS_LIB"pure_quanta_power"
HDL_POWER"GND";
"A"30;
%"Q_CAPP"
"1","(-1800,2925)","0","pure_quanta","I73";
;
LOCATION"PC389"
$SEC"1"
CDS_SEC"1"
PACK_TYPE"SMLF"
VALUE"220UF"
TOLERANCE"20%"
MATERIAL"SPCAP"
VOLTAGE"4V"
CDS_LIB"pure_quanta"
PART_NUMBER"CH122KM8801";
"A"
$PN"1"31;
"B"
$PN"2"30;
%"Q_CAPP"
"1","(-1500,2925)","0","pure_quanta","I74";
;
LOCATION"PC391"
$SEC"1"
CDS_SEC"1"
MATERIAL"SPCAP"
VALUE"220UF"
TOLERANCE"20%"
VOLTAGE"4V"
PACK_TYPE"SMLF"
CDS_LIB"pure_quanta"
PART_NUMBER"CH122KM8801";
"A"
$PN"1"31;
"B"
$PN"2"30;
%"VCC_CORE"
"1","(-1500,3225)","0","pure_quanta_power","I75";
;
HDL_POWER"PVDDCR_CPU1_P1"
CDS_LIB"pure_quanta_power";
"A"31;
%"UNIVERSAL_GND"
"1","(-900,4025)","0","pure_quanta_power","I76";
;
CDS_LIB"pure_quanta_power"
HDL_POWER"GND";
"A"32;
%"Q_INDUCTOR4P_14"
"1","(-3450,4475)","0","pure_quanta","I77";
;
LOCATION"PL40"
$SEC"1"
CDS_SEC"1"
PART_TYPE"SMLF"
MATERIAL"IND"
VALUE"150NH"
CDS_LIB"pure_quanta"
NEEDS_NO_SIZE"TRUE"
PART_NUMBER"CV+15^0TZ04";
"1"
$PN"1"35;
"4"
$PN"4"19;
"3"
$PN"3"61;
"2"
$PN"2"58;
%"Q_INDUCTOR"
"1","(-3350,5775)","0","pure_quanta","I79";
;
LOCATION"PL42"
$SEC"1"
CDS_SEC"1"
PACK_TYPE"SMLF"
VALUE"50NH/86A"
MATERIAL"IND"
NEEDS_NO_SIZE"TRUE"
CDS_LIB"pure_quanta"
PART_NUMBER"CVA50^0MZ09";
"1"
$PN"1"20;
"2"
$PN"2"13;
%"UNIVERSAL_GND"
"1","(-2875,5175)","0","pure_quanta_power","I81";
;
CDS_LIB"pure_quanta_power"
HDL_POWER"GND";
"A"12;
%"Q_CAP"
"1","(-2025,4400)","0","pure_quanta","I82";
;
LOCATION"PC392"
$SEC"1"
CDS_SEC"1"
MATERIAL"X7R"
TOLERANCE"10%"
VALUE"0.1UF"
VOLTAGE"25V"
PACK_TYPE"0402"
CDS_LIB"pure_quanta"
PART_NUMBER"CH4104K1B00";
"B"
$PN"2"32;
"A"
$PN"1"19;
%"Q_CAP"
"1","(-2875,5550)","0","pure_quanta","I83";
;
LOCATION"PC375"
$SEC"1"
CDS_SEC"1"
VALUE"0.1UF"
TOLERANCE"10%"
MATERIAL"X7R"
PACK_TYPE"0402"
VOLTAGE"25V"
CDS_LIB"pure_quanta"
PART_NUMBER"CH4104K1B00";
"B"
$PN"2"12;
"A"
$PN"1"13;
%"VCC_CORE"
"1","(-2875,5875)","0","pure_quanta_power","I84";
;
HDL_POWER"P12V_AUX"
CDS_LIB"pure_quanta_power";
"A"13;
%"Q_CAP"
"1","(-1675,4400)","0","pure_quanta","I85";
;
LOCATION"PC395_1"
$SEC"1"
CDS_SEC"1"
VOLTAGE"4V"
VALUE"22UF"
MATERIAL"X6S"
PACK_TYPE"C0805"
TOLERANCE"20%"
CDS_LIB"pure_quanta"
PART_NUMBER"CH622KMEA03";
"B"
$PN"2"32;
"A"
$PN"1"19;
%"Q_CAP"
"1","(-1250,4400)","0","pure_quanta","I86";
;
LOCATION"PC398_1"
$SEC"1"
CDS_SEC"1"
VOLTAGE"4V"
VALUE"22UF"
TOLERANCE"20%"
MATERIAL"X6S"
PACK_TYPE"C0805"
CDS_LIB"pure_quanta"
PART_NUMBER"CH622KMEA03";
"B"
$PN"2"32;
"A"
$PN"1"19;
%"Q_RES"
"2","(-900,4400)","0","pure_quanta","I87";
;
LOCATION"PR342"
$SEC"1"
CDS_SEC"1"
PACK_TYPE"0402LF"
VALUE"1K"
TOLERANCE"1%"
MATERIAL"CHIP"
WATTAGE"1/16W"
CDS_LIB"pure_quanta"
PART_NUMBER"CS21002FB06";
"A"
$PN"1"19;
"B"
$PN"2"32;
%"VCC_CORE"
"1","(-900,4750)","0","pure_quanta_power","I88";
;
HDL_POWER"PVDDCR_CPU1_P1"
CDS_LIB"pure_quanta_power";
"A"19;
%"Q_RES"
"1","(-9225,6000)","1","pure_quanta","I89";
;
LOCATION"PR340"
$SEC"1"
CDS_SEC"1"
VALUE"0"
PACK_TYPE"0402LF"
TOLERANCE"5%"
MATERIAL"CHIP"
WATTAGE"1/16W"
CDS_LIB"pure_quanta"
PART_NUMBER"CS00002JB13";
"B"
$PN"2"5;
"A"
$PN"1"23;
%"UNIVERSAL_GND"
"1","(-8475,2200)","0","pure_quanta_power","I9";
;
CDS_LIB"pure_quanta_power"
HDL_POWER"GND";
"A"14;
%"Q_RES"
"1","(-8875,6000)","1","pure_quanta","I90";
;
LOCATION"PR341"
$SEC"1"
CDS_SEC"1"
TOLERANCE"5%"
PACK_TYPE"0402LF"
MATERIAL"EMPTY"
WATTAGE"1/16W"
VALUE"0"
CDS_LIB"pure_quanta"
PART_NUMBER"CS00002JB13";
"B"
$PN"2"7;
"A"
$PN"1"23;
%"ISL99390FRZTR5935"
"1","(-6800,4600)","0","pure_quanta","I91";
;
LOCATION"PU35"
$SEC"1"
CDS_SEC"1"
MATERIAL"IC"
VALUE"ISL99390FRZ-TR5935"
PART_TYPE"SMLF"
NEEDS_NO_SIZE"TRUE"
CDS_LMAN_SYM_OUTLINE"-300,700,250,-650"
CDS_LIB"pure_quanta"
PART_NUMBER"AL099390004";
"PGND2"
$PN"7_9-20_24"25;
"GL2"
$PN"41"57;
"GL1"
$PN"6"56;
"DNC"
$PN"31"54;
"EN"
$PN"35"55;
"PGND3"
$PN"40"25;
"VOS"
$PN"1"34;
"VIN2"
$PN"30"20;
"PGND1"
$PN"5"25;
"SW"
$PN"10_19"35;
"LSET"
$PN"37"41;
"IOUT"
$PN"38"42;
"TOUT_FLT"
$PN"36"43;
"PVCC"
$PN"4"23;
"PHASE"
$PN"32"36;
"VIN1"
$PN"25_29"20;
"BOOT"
$PN"33"37;
"AGND"
$PN"2"25;
"VCC"
$PN"3"55;
"REFIN"
$PN"39"62;
"PWM"
$PN"34"44;
%"Q_CAPP"
"1","(-3725,5500)","0","pure_quanta","I92";
;
LOCATION"PC393"
$SEC"1"
CDS_SEC"1"
VALUE"270UF"
TOLERANCE"20%"
VOLTAGE"16V"
PACK_TYPE"SMLF"
MATERIAL"OSCON"
CDS_LIB"pure_quanta"
PART_NUMBER"CC72703MZ11";
"A"
$PN"1"20;
"B"
$PN"2"21;
%"Q_CAPP"
"1","(-4125,5500)","0","pure_quanta","I93";
;
LOCATION"PC390"
$SEC"1"
CDS_SEC"1"
VOLTAGE"16V"
PACK_TYPE"SMLF"
MATERIAL"OSCON"
TOLERANCE"20%"
VALUE"270UF"
CDS_LIB"pure_quanta"
PART_NUMBER"CC72703MZ11";
"A"
$PN"1"20;
"B"
$PN"2"21;
END.
